(kicad_pcb
	(version 20260206)
	(generator "pcbnew")
	(generator_version "10.0")
	(general
		(thickness 1.6)
		(legacy_teardrops no)
	)
	(paper "A4")
	(title_block
		(title "01162023_DA0F0TEBIF0_F0T_Expander_BD_F_brd_V02_OCP.brd")
		(comment 1 "Grand Teton / footprints 4098-4104 of 9728")
	)
	(layers
		(0 "F.Cu" signal "TOP")
		(4 "In1.Cu" signal "GND")
		(6 "In2.Cu" signal "VCC")
		(8 "In3.Cu" signal "VCC1")
		(10 "In4.Cu" signal "GND1")
		(12 "In5.Cu" signal "IN1")
		(14 "In6.Cu" signal "GND2")
		(16 "In7.Cu" signal "IN2")
		(18 "In8.Cu" signal "GND3")
		(20 "In9.Cu" signal "IN3")
		(22 "In10.Cu" signal "GND4")
		(24 "In11.Cu" signal "IN4")
		(26 "In12.Cu" signal "GND5")
		(28 "In13.Cu" signal "IN5")
		(30 "In14.Cu" signal "GND6")
		(32 "In15.Cu" signal "IN6")
		(34 "In16.Cu" signal "GND7")
		(2 "B.Cu" signal "BOTTOM")
		(9 "F.Adhes" user "F.Adhesive")
		(11 "B.Adhes" user "B.Adhesive")
		(13 "F.Paste" user "Package Geometry/Pastemask Top")
		(15 "B.Paste" user "Package Geometry/Pastemask Bottom")
		(5 "F.SilkS" user "Ref Des/Silkscreen Top")
		(7 "B.SilkS" user "Ref Des/Silkscreen Bottom")
		(1 "F.Mask" user "Board Geometry/Soldermask Top")
		(3 "B.Mask" user "Board Geometry/Soldermask Bottom")
		(17 "Dwgs.User" user "User.Drawings")
		(19 "Cmts.User" user "User.Comments")
		(21 "Eco1.User" user "User.Eco1")
		(23 "Eco2.User" user "User.Eco2")
		(25 "Edge.Cuts" user "Board Geometry/Outline")
		(27 "Margin" user)
		(31 "F.CrtYd" user "Package Geometry/Place Bound Top")
		(29 "B.CrtYd" user "Package Geometry/Place Bound Bottom")
		(35 "F.Fab" user "Ref Des/Assembly Top")
		(33 "B.Fab" user "Ref Des/Assembly Bottom")
	)
	(footprint ""
		(layer "F.Cu")
		(at 420.425372 -42.849038 180)
		(property "Reference" "R667"
			(at 0 0 180)
			(layer "F.SilkS")
			(hide yes)
			(effects
				(font
					(size 1.27 1.27)
				)
			)
		)
		(property "Value" ""
			(at 0 0 180)
			(layer "F.Fab")
			(effects
				(font
					(size 1.27 1.27)
				)
			)
		)
		(duplicate_pad_numbers_are_jumpers no)
		(fp_line
			(start 0.7874 0.4064)
			(end -0.7874 0.4064)
			(stroke
				(width 0.1524)
				(type default)
			)
			(layer "F.SilkS")
		)
		(fp_line
			(start 0.7874 -0.4064)
			(end 0.7874 0.4064)
			(stroke
				(width 0.1524)
				(type default)
			)
			(layer "F.SilkS")
		)
		(fp_line
			(start -0.7874 0.4064)
			(end -0.7874 -0.4064)
			(stroke
				(width 0.1524)
				(type default)
			)
			(layer "F.SilkS")
		)
		(fp_line
			(start -0.7874 -0.4064)
			(end 0.7874 -0.4064)
			(stroke
				(width 0.1524)
				(type default)
			)
			(layer "F.SilkS")
		)
		(fp_line
			(start 0.67945 0.3048)
			(end 0.120396 0.3048)
			(stroke
				(width 0.1)
				(type default)
			)
			(layer "F.Fab")
		)
		(fp_line
			(start 0.67945 -0.3048)
			(end 0.67945 0.3048)
			(stroke
				(width 0.1)
				(type default)
			)
			(layer "F.Fab")
		)
		(fp_line
			(start 0.12065 -0.2794)
			(end 0.12065 -0.3048)
			(stroke
				(width 0.1)
				(type default)
			)
			(layer "F.Fab")
		)
		(fp_line
			(start 0.12065 -0.3048)
			(end 0.67945 -0.3048)
			(stroke
				(width 0.1)
				(type default)
			)
			(layer "F.Fab")
		)
		(fp_line
			(start 0.120396 0.3048)
			(end 0.120396 0.2794)
			(stroke
				(width 0.1)
				(type default)
			)
			(layer "F.Fab")
		)
		(fp_line
			(start 0.120396 0.2794)
			(end -0.12065 0.2794)
			(stroke
				(width 0.1)
				(type default)
			)
			(layer "F.Fab")
		)
		(fp_line
			(start -0.12065 0.3048)
			(end -0.67945 0.3048)
			(stroke
				(width 0.1)
				(type default)
			)
			(layer "F.Fab")
		)
		(fp_line
			(start -0.12065 0.2794)
			(end -0.12065 0.3048)
			(stroke
				(width 0.1)
				(type default)
			)
			(layer "F.Fab")
		)
		(fp_line
			(start -0.12065 -0.2794)
			(end 0.12065 -0.2794)
			(stroke
				(width 0.1)
				(type default)
			)
			(layer "F.Fab")
		)
		(fp_line
			(start -0.12065 -0.305054)
			(end -0.12065 -0.2794)
			(stroke
				(width 0.1)
				(type default)
			)
			(layer "F.Fab")
		)
		(fp_line
			(start -0.67945 0.3048)
			(end -0.67945 -0.305054)
			(stroke
				(width 0.1)
				(type default)
			)
			(layer "F.Fab")
		)
		(fp_line
			(start -0.67945 -0.305054)
			(end -0.12065 -0.305054)
			(stroke
				(width 0.1)
				(type default)
			)
			(layer "F.Fab")
		)
		(pad "1" smd circle
			(at -0.40005 0 180)
			(size 0 0)
			(layers "F.Cu" "F.Mask" "F.Paste")
			(net "P12V_SSD14_R")
		)
		(pad "2" smd circle
			(at 0.40005 0 180)
			(size 0 0)
			(layers "F.Cu" "F.Mask" "F.Paste")
			(net "P12V_SSD14_VIN_P")
		)
	)
	(footprint ""
		(layer "F.Cu")
		(at 146.18208 -292.991032 180)
		(property "Reference" "C3206"
			(at 0 0 180)
			(layer "F.SilkS")
			(hide yes)
			(effects
				(font
					(size 1.27 1.27)
				)
			)
		)
		(property "Value" ""
			(at 0 0 180)
			(layer "F.Fab")
			(effects
				(font
					(size 1.27 1.27)
				)
			)
		)
		(duplicate_pad_numbers_are_jumpers no)
		(fp_line
			(start 1.2954 0.5842)
			(end -1.2954 0.5842)
			(stroke
				(width 0.1524)
				(type default)
			)
			(layer "F.SilkS")
		)
		(fp_line
			(start 1.2954 -0.5842)
			(end 1.2954 0.5842)
			(stroke
				(width 0.1524)
				(type default)
			)
			(layer "F.SilkS")
		)
		(fp_line
			(start -1.2954 0.5842)
			(end -1.2954 -0.5842)
			(stroke
				(width 0.1524)
				(type default)
			)
			(layer "F.SilkS")
		)
		(fp_line
			(start -1.2954 -0.5842)
			(end 1.2954 -0.5842)
			(stroke
				(width 0.1524)
				(type default)
			)
			(layer "F.SilkS")
		)
		(fp_line
			(start 1.1938 0.4064)
			(end 0.8636 0.4064)
			(stroke
				(width 0.1)
				(type default)
			)
			(layer "F.Fab")
		)
		(fp_line
			(start 1.1938 -0.4064)
			(end 1.1938 0.4064)
			(stroke
				(width 0.1)
				(type default)
			)
			(layer "F.Fab")
		)
		(fp_line
			(start 0.8636 0.4572)
			(end -0.8636 0.4572)
			(stroke
				(width 0.1)
				(type default)
			)
			(layer "F.Fab")
		)
		(fp_line
			(start 0.8636 0.4064)
			(end 0.8636 0.4572)
			(stroke
				(width 0.1)
				(type default)
			)
			(layer "F.Fab")
		)
		(fp_line
			(start 0.8636 -0.4064)
			(end 1.1938 -0.4064)
			(stroke
				(width 0.1)
				(type default)
			)
			(layer "F.Fab")
		)
		(fp_line
			(start 0.8636 -0.4572)
			(end 0.8636 -0.4064)
			(stroke
				(width 0.1)
				(type default)
			)
			(layer "F.Fab")
		)
		(fp_line
			(start -0.8636 0.4572)
			(end -0.8636 0.4064)
			(stroke
				(width 0.1)
				(type default)
			)
			(layer "F.Fab")
		)
		(fp_line
			(start -0.8636 0.4064)
			(end -1.1938 0.4064)
			(stroke
				(width 0.1)
				(type default)
			)
			(layer "F.Fab")
		)
		(fp_line
			(start -0.8636 -0.4064)
			(end -0.8636 -0.4572)
			(stroke
				(width 0.1)
				(type default)
			)
			(layer "F.Fab")
		)
		(fp_line
			(start -0.8636 -0.4572)
			(end 0.8636 -0.4572)
			(stroke
				(width 0.1)
				(type default)
			)
			(layer "F.Fab")
		)
		(fp_line
			(start -1.1938 0.4064)
			(end -1.1938 -0.4064)
			(stroke
				(width 0.1)
				(type default)
			)
			(layer "F.Fab")
		)
		(fp_line
			(start -1.1938 -0.4064)
			(end -0.8636 -0.4064)
			(stroke
				(width 0.1)
				(type default)
			)
			(layer "F.Fab")
		)
		(pad "1" smd rect
			(at -0.7366 0 90)
			(size 0.7112 0.8128)
			(layers "F.Cu" "F.Mask" "F.Paste")
			(net "PCEPLL2_VDDA18_PEX1_R")
		)
		(pad "2" smd rect
			(at 0.7366 0 90)
			(size 0.7112 0.8128)
			(layers "F.Cu" "F.Mask" "F.Paste")
			(net "GND")
		)
	)
	(footprint ""
		(layer "F.Cu")
		(at 319.977262 -309.791354 135)
		(property "Reference" "R1377"
			(at 0 0 135)
			(layer "F.SilkS")
			(hide yes)
			(effects
				(font
					(size 1.27 1.27)
				)
			)
		)
		(property "Value" ""
			(at 0 0 135)
			(layer "F.Fab")
			(effects
				(font
					(size 1.27 1.27)
				)
			)
		)
		(duplicate_pad_numbers_are_jumpers no)
		(fp_line
			(start 0.787389 -0.406267)
			(end 0.787389 0.406267)
			(stroke
				(width 0.1524)
				(type default)
			)
			(layer "F.SilkS")
		)
		(fp_line
			(start 0.787389 0.406267)
			(end -0.787389 0.406267)
			(stroke
				(width 0.1524)
				(type default)
			)
			(layer "F.SilkS")
		)
		(fp_line
			(start -0.787389 -0.406267)
			(end 0.787389 -0.406267)
			(stroke
				(width 0.1524)
				(type default)
			)
			(layer "F.SilkS")
		)
		(fp_line
			(start -0.787389 0.406267)
			(end -0.787389 -0.406267)
			(stroke
				(width 0.1524)
				(type default)
			)
			(layer "F.SilkS")
		)
		(fp_line
			(start 0.679446 -0.30479)
			(end 0.679446 0.30479)
			(stroke
				(width 0.1)
				(type default)
			)
			(layer "F.Fab")
		)
		(fp_line
			(start 0.120515 -0.30479)
			(end 0.679446 -0.30479)
			(stroke
				(width 0.1)
				(type default)
			)
			(layer "F.Fab")
		)
		(fp_line
			(start 0.120695 -0.279466)
			(end 0.120515 -0.30479)
			(stroke
				(width 0.1)
				(type default)
			)
			(layer "F.Fab")
		)
		(fp_line
			(start 0.679446 0.30479)
			(end 0.120515 0.30479)
			(stroke
				(width 0.1)
				(type default)
			)
			(layer "F.Fab")
		)
		(fp_line
			(start -0.120695 -0.304969)
			(end -0.120695 -0.279466)
			(stroke
				(width 0.1)
				(type default)
			)
			(layer "F.Fab")
		)
		(fp_line
			(start -0.120695 -0.279466)
			(end 0.120695 -0.279466)
			(stroke
				(width 0.1)
				(type default)
			)
			(layer "F.Fab")
		)
		(fp_line
			(start 0.120335 0.279466)
			(end -0.120695 0.279466)
			(stroke
				(width 0.1)
				(type default)
			)
			(layer "F.Fab")
		)
		(fp_line
			(start 0.120515 0.30479)
			(end 0.120335 0.279466)
			(stroke
				(width 0.1)
				(type default)
			)
			(layer "F.Fab")
		)
		(fp_line
			(start -0.679446 -0.305149)
			(end -0.120695 -0.304969)
			(stroke
				(width 0.1)
				(type default)
			)
			(layer "F.Fab")
		)
		(fp_line
			(start -0.120695 0.279466)
			(end -0.120515 0.30479)
			(stroke
				(width 0.1)
				(type default)
			)
			(layer "F.Fab")
		)
		(fp_line
			(start -0.120515 0.30479)
			(end -0.679446 0.30479)
			(stroke
				(width 0.1)
				(type default)
			)
			(layer "F.Fab")
		)
		(fp_line
			(start -0.679446 0.30479)
			(end -0.679446 -0.305149)
			(stroke
				(width 0.1)
				(type default)
			)
			(layer "F.Fab")
		)
		(pad "1" smd circle
			(at -0.40005 0 135)
			(size 0 0)
			(layers "F.Cu" "F.Mask" "F.Paste")
			(net "PEX2_SPARE7")
		)
		(pad "2" smd circle
			(at 0.40005 0 135)
			(size 0 0)
			(layers "F.Cu" "F.Mask" "F.Paste")
			(net "P1V8_PEX")
		)
	)
	(footprint ""
		(layer "F.Cu")
		(at 98.947224 -20.35556)
		(property "Reference" "C3895"
			(at 0 0 0)
			(layer "F.SilkS")
			(hide yes)
			(effects
				(font
					(size 1.27 1.27)
				)
			)
		)
		(property "Value" ""
			(at 0 0 0)
			(layer "F.Fab")
			(effects
				(font
					(size 1.27 1.27)
				)
			)
		)
		(duplicate_pad_numbers_are_jumpers no)
		(fp_line
			(start -0.7874 -0.4064)
			(end 0.7874 -0.4064)
			(stroke
				(width 0.1524)
				(type default)
			)
			(layer "F.SilkS")
		)
		(fp_line
			(start -0.7874 0.4064)
			(end -0.7874 -0.4064)
			(stroke
				(width 0.1524)
				(type default)
			)
			(layer "F.SilkS")
		)
		(fp_line
			(start 0.7874 -0.4064)
			(end 0.7874 0.4064)
			(stroke
				(width 0.1524)
				(type default)
			)
			(layer "F.SilkS")
		)
		(fp_line
			(start 0.7874 0.4064)
			(end -0.7874 0.4064)
			(stroke
				(width 0.1524)
				(type default)
			)
			(layer "F.SilkS")
		)
		(fp_line
			(start -0.67945 -0.305054)
			(end -0.12065 -0.305054)
			(stroke
				(width 0.1)
				(type default)
			)
			(layer "F.Fab")
		)
		(fp_line
			(start -0.67945 0.3048)
			(end -0.67945 -0.305054)
			(stroke
				(width 0.1)
				(type default)
			)
			(layer "F.Fab")
		)
		(fp_line
			(start -0.12065 -0.305054)
			(end -0.12065 -0.2794)
			(stroke
				(width 0.1)
				(type default)
			)
			(layer "F.Fab")
		)
		(fp_line
			(start -0.12065 -0.2794)
			(end 0.12065 -0.2794)
			(stroke
				(width 0.1)
				(type default)
			)
			(layer "F.Fab")
		)
		(fp_line
			(start -0.12065 0.2794)
			(end -0.12065 0.3048)
			(stroke
				(width 0.1)
				(type default)
			)
			(layer "F.Fab")
		)
		(fp_line
			(start -0.12065 0.3048)
			(end -0.67945 0.3048)
			(stroke
				(width 0.1)
				(type default)
			)
			(layer "F.Fab")
		)
		(fp_line
			(start 0.120396 0.2794)
			(end -0.12065 0.2794)
			(stroke
				(width 0.1)
				(type default)
			)
			(layer "F.Fab")
		)
		(fp_line
			(start 0.120396 0.3048)
			(end 0.120396 0.2794)
			(stroke
				(width 0.1)
				(type default)
			)
			(layer "F.Fab")
		)
		(fp_line
			(start 0.12065 -0.3048)
			(end 0.67945 -0.3048)
			(stroke
				(width 0.1)
				(type default)
			)
			(layer "F.Fab")
		)
		(fp_line
			(start 0.12065 -0.2794)
			(end 0.12065 -0.3048)
			(stroke
				(width 0.1)
				(type default)
			)
			(layer "F.Fab")
		)
		(fp_line
			(start 0.67945 -0.3048)
			(end 0.67945 0.3048)
			(stroke
				(width 0.1)
				(type default)
			)
			(layer "F.Fab")
		)
		(fp_line
			(start 0.67945 0.3048)
			(end 0.120396 0.3048)
			(stroke
				(width 0.1)
				(type default)
			)
			(layer "F.Fab")
		)
		(pad "1" smd circle
			(at -0.40005 0)
			(size 0 0)
			(layers "F.Cu" "F.Mask" "F.Paste")
			(net "P12V_SSD3")
		)
		(pad "2" smd circle
			(at 0.40005 0)
			(size 0 0)
			(layers "F.Cu" "F.Mask" "F.Paste")
			(net "GND")
		)
	)
	(footprint ""
		(layer "F.Cu")
		(at 134.30758 -152.71115 90)
		(property "Reference" "R706"
			(at 0 0 90)
			(layer "F.SilkS")
			(hide yes)
			(effects
				(font
					(size 1.27 1.27)
				)
			)
		)
		(property "Value" ""
			(at 0 0 90)
			(layer "F.Fab")
			(effects
				(font
					(size 1.27 1.27)
				)
			)
		)
		(duplicate_pad_numbers_are_jumpers no)
		(fp_line
			(start 0.7874 -0.4064)
			(end 0.7874 0.4064)
			(stroke
				(width 0.1524)
				(type default)
			)
			(layer "F.SilkS")
		)
		(fp_line
			(start -0.7874 -0.4064)
			(end 0.7874 -0.4064)
			(stroke
				(width 0.1524)
				(type default)
			)
			(layer "F.SilkS")
		)
		(fp_line
			(start 0.7874 0.4064)
			(end -0.7874 0.4064)
			(stroke
				(width 0.1524)
				(type default)
			)
			(layer "F.SilkS")
		)
		(fp_line
			(start -0.7874 0.4064)
			(end -0.7874 -0.4064)
			(stroke
				(width 0.1524)
				(type default)
			)
			(layer "F.SilkS")
		)
		(fp_line
			(start -0.12065 -0.305054)
			(end -0.12065 -0.2794)
			(stroke
				(width 0.1)
				(type default)
			)
			(layer "F.Fab")
		)
		(fp_line
			(start -0.67945 -0.305054)
			(end -0.12065 -0.305054)
			(stroke
				(width 0.1)
				(type default)
			)
			(layer "F.Fab")
		)
		(fp_line
			(start 0.67945 -0.3048)
			(end 0.67945 0.3048)
			(stroke
				(width 0.1)
				(type default)
			)
			(layer "F.Fab")
		)
		(fp_line
			(start 0.12065 -0.3048)
			(end 0.67945 -0.3048)
			(stroke
				(width 0.1)
				(type default)
			)
			(layer "F.Fab")
		)
		(fp_line
			(start 0.12065 -0.2794)
			(end 0.12065 -0.3048)
			(stroke
				(width 0.1)
				(type default)
			)
			(layer "F.Fab")
		)
		(fp_line
			(start -0.12065 -0.2794)
			(end 0.12065 -0.2794)
			(stroke
				(width 0.1)
				(type default)
			)
			(layer "F.Fab")
		)
		(fp_line
			(start 0.120396 0.2794)
			(end -0.12065 0.2794)
			(stroke
				(width 0.1)
				(type default)
			)
			(layer "F.Fab")
		)
		(fp_line
			(start -0.12065 0.2794)
			(end -0.12065 0.3048)
			(stroke
				(width 0.1)
				(type default)
			)
			(layer "F.Fab")
		)
		(fp_line
			(start 0.67945 0.3048)
			(end 0.120396 0.3048)
			(stroke
				(width 0.1)
				(type default)
			)
			(layer "F.Fab")
		)
		(fp_line
			(start 0.120396 0.3048)
			(end 0.120396 0.2794)
			(stroke
				(width 0.1)
				(type default)
			)
			(layer "F.Fab")
		)
		(fp_line
			(start -0.12065 0.3048)
			(end -0.67945 0.3048)
			(stroke
				(width 0.1)
				(type default)
			)
			(layer "F.Fab")
		)
		(fp_line
			(start -0.67945 0.3048)
			(end -0.67945 -0.305054)
			(stroke
				(width 0.1)
				(type default)
			)
			(layer "F.Fab")
		)
		(pad "1" smd circle
			(at -0.40005 0 90)
			(size 0 0)
			(layers "F.Cu" "F.Mask" "F.Paste")
			(net "NIC2_ADC_ALERT_N")
		)
		(pad "2" smd circle
			(at 0.40005 0 90)
			(size 0 0)
			(layers "F.Cu" "F.Mask" "F.Paste")
			(net "NIC_ADC_ALERT_N")
		)
	)
	(footprint ""
		(layer "F.Cu")
		(at 54.875176 -64.102234 180)
		(property "Reference" "PR6913"
			(at 0 0 180)
			(layer "F.SilkS")
			(hide yes)
			(effects
				(font
					(size 1.27 1.27)
				)
			)
		)
		(property "Value" ""
			(at 0 0 180)
			(layer "F.Fab")
			(effects
				(font
					(size 1.27 1.27)
				)
			)
		)
		(duplicate_pad_numbers_are_jumpers no)
		(fp_line
			(start 0.7874 0.4064)
			(end -0.7874 0.4064)
			(stroke
				(width 0.1524)
				(type default)
			)
			(layer "F.SilkS")
		)
		(fp_line
			(start 0.7874 -0.4064)
			(end 0.7874 0.4064)
			(stroke
				(width 0.1524)
				(type default)
			)
			(layer "F.SilkS")
		)
		(fp_line
			(start -0.7874 0.4064)
			(end -0.7874 -0.4064)
			(stroke
				(width 0.1524)
				(type default)
			)
			(layer "F.SilkS")
		)
		(fp_line
			(start -0.7874 -0.4064)
			(end 0.7874 -0.4064)
			(stroke
				(width 0.1524)
				(type default)
			)
			(layer "F.SilkS")
		)
		(fp_line
			(start 0.67945 0.3048)
			(end 0.120396 0.3048)
			(stroke
				(width 0.1)
				(type default)
			)
			(layer "F.Fab")
		)
		(fp_line
			(start 0.67945 -0.3048)
			(end 0.67945 0.3048)
			(stroke
				(width 0.1)
				(type default)
			)
			(layer "F.Fab")
		)
		(fp_line
			(start 0.12065 -0.2794)
			(end 0.12065 -0.3048)
			(stroke
				(width 0.1)
				(type default)
			)
			(layer "F.Fab")
		)
		(fp_line
			(start 0.12065 -0.3048)
			(end 0.67945 -0.3048)
			(stroke
				(width 0.1)
				(type default)
			)
			(layer "F.Fab")
		)
		(fp_line
			(start 0.120396 0.3048)
			(end 0.120396 0.2794)
			(stroke
				(width 0.1)
				(type default)
			)
			(layer "F.Fab")
		)
		(fp_line
			(start 0.120396 0.2794)
			(end -0.12065 0.2794)
			(stroke
				(width 0.1)
				(type default)
			)
			(layer "F.Fab")
		)
		(fp_line
			(start -0.12065 0.3048)
			(end -0.67945 0.3048)
			(stroke
				(width 0.1)
				(type default)
			)
			(layer "F.Fab")
		)
		(fp_line
			(start -0.12065 0.2794)
			(end -0.12065 0.3048)
			(stroke
				(width 0.1)
				(type default)
			)
			(layer "F.Fab")
		)
		(fp_line
			(start -0.12065 -0.2794)
			(end 0.12065 -0.2794)
			(stroke
				(width 0.1)
				(type default)
			)
			(layer "F.Fab")
		)
		(fp_line
			(start -0.12065 -0.305054)
			(end -0.12065 -0.2794)
			(stroke
				(width 0.1)
				(type default)
			)
			(layer "F.Fab")
		)
		(fp_line
			(start -0.67945 0.3048)
			(end -0.67945 -0.305054)
			(stroke
				(width 0.1)
				(type default)
			)
			(layer "F.Fab")
		)
		(fp_line
			(start -0.67945 -0.305054)
			(end -0.12065 -0.305054)
			(stroke
				(width 0.1)
				(type default)
			)
			(layer "F.Fab")
		)
		(pad "1" smd circle
			(at -0.40005 0 180)
			(size 0 0)
			(layers "F.Cu" "F.Mask" "F.Paste")
			(net "P12V_SSD2_PG_G1")
		)
		(pad "2" smd circle
			(at 0.40005 0 180)
			(size 0 0)
			(layers "F.Cu" "F.Mask" "F.Paste")
			(net "GND")
		)
	)
	(footprint ""
		(layer "F.Cu")
		(at 486.96753 -526.47723 180)
		(property "Reference" "J36_OTH"
			(at -3.2385 -1.402334 0)
			(unlocked yes)
			(layer "B.SilkS")
			(effects
				(font
					(size 0.7874 0.5842)
					(thickness 0.1524)
				)
				(justify mirror)
			)
		)
		(property "Value" ""
			(at 0 0 180)
			(layer "F.Fab")
			(effects
				(font
					(size 1.27 1.27)
				)
			)
		)
		(duplicate_pad_numbers_are_jumpers no)
		(pad "1" thru_hole circle
			(at 0 0 180)
			(size 0.4572 0.4572)
			(drill 0.2032)
			(layers "*.Cu" "*.Mask")
			(remove_unused_layers no)
			(net "Net_9100")
			(clearance 0.127)
			(thermal_gap 0.127)
			(padstack
				(mode front_inner_back)
				(layer "Inner"
					(shape circle)
					(size 0.4572 0.4572)
					(clearance 0.127)
				)
				(layer "B.Cu"
					(shape circle)
					(size 0.508 0.508)
					(clearance 0.1016)
				)
			)
		)
	)
)
